(kicad_pcb
	(version 20260206)
	(generator "pcbnew")
	(generator_version "10.0")
	(general
		(thickness 1.6)
		(legacy_teardrops no)
	)
	(paper "A4")
	(title_block
		(title "Bryce Canyon_R.DPB_16317-1_OCP.brd")
		(comment 1 "Bryce Canyon / footprints 1512-1519 of 2099")
	)
	(layers
		(0 "F.Cu" signal "TOP")
		(4 "In1.Cu" signal "L2GND")
		(6 "In2.Cu" signal "L3")
		(8 "In3.Cu" signal "L4VCC")
		(10 "In4.Cu" signal "L5VCC")
		(12 "In5.Cu" signal "L6")
		(14 "In6.Cu" signal "L7GND")
		(2 "B.Cu" signal "BOTTOM")
		(9 "F.Adhes" user "F.Adhesive")
		(11 "B.Adhes" user "B.Adhesive")
		(13 "F.Paste" user "Package Geometry/Pastemask Top")
		(15 "B.Paste" user "Package Geometry/Pastemask Bottom")
		(5 "F.SilkS" user "Ref Des/Silkscreen Top")
		(7 "B.SilkS" user "Ref Des/Silkscreen Bottom")
		(1 "F.Mask" user "Board Geometry/Soldermask Top")
		(3 "B.Mask" user "Board Geometry/Soldermask Bottom")
		(17 "Dwgs.User" user "User.Drawings")
		(19 "Cmts.User" user "User.Comments")
		(21 "Eco1.User" user "User.Eco1")
		(23 "Eco2.User" user "User.Eco2")
		(25 "Edge.Cuts" user "Board Geometry/Outline")
		(27 "Margin" user)
		(31 "F.CrtYd" user "Package Geometry/Place Bound Top")
		(29 "B.CrtYd" user "Package Geometry/Place Bound Bottom")
		(35 "F.Fab" user "Ref Des/Assembly Top")
		(33 "B.Fab" user "Ref Des/Assembly Bottom")
	)
	(footprint ""
		(layer "F.Cu")
		(at 253.451614 -140.228574 -90)
		(property "Reference" "R447"
			(at 0 0 270)
			(layer "F.SilkS")
			(hide yes)
			(effects
				(font
					(size 1.27 1.27)
				)
			)
		)
		(property "Value" "1KR2J-1-GP"
			(at 0.064008 -3.993896 270)
			(unlocked yes)
			(layer "F.Fab")
			(hide yes)
			(effects
				(font
					(size 1.016 1.016)
					(thickness 0.1524)
				)
			)
		)
		(property "Device Type" "R402H16"
			(at 0.064008 -5.517896 270)
			(unlocked yes)
			(layer "F.Fab")
			(hide yes)
			(effects
				(font
					(size 1.016 1.016)
					(thickness 0.1524)
				)
			)
		)
		(duplicate_pad_numbers_are_jumpers no)
		(fp_line
			(start -0.508 -0.9398)
			(end -0.508 0.9398)
			(stroke
				(width 0.1524)
				(type default)
			)
			(layer "F.SilkS")
		)
		(fp_line
			(start 0.508 -0.9398)
			(end -0.508 -0.9398)
			(stroke
				(width 0.1524)
				(type default)
			)
			(layer "F.SilkS")
		)
		(fp_rect
			(start -0.508 0.9398)
			(end 0.508 -0.9398)
			(stroke
				(width 0)
				(type default)
			)
			(fill no)
			(layer "F.CrtYd")
		)
		(fp_rect
			(start -0.508 0.9398)
			(end 0.508 -0.9398)
			(stroke
				(width 0)
				(type default)
			)
			(fill no)
			(layer "F.Fab")
		)
		(pad "1" smd custom
			(at 0 -0.4445 270)
			(size 0.1397 0.1397)
			(layers "F.Cu" "F.Mask" "F.Paste")
			(net "P3V3_STBY_B")
			(options
				(clearance outline)
				(anchor circle)
			)
			(primitives
				(gr_poly
					(pts
						(arc
							(start -0.1778 -0.2794)
							(mid -0.249642 -0.249642)
							(end -0.2794 -0.1778)
						)
						(arc
							(start -0.2794 0.1778)
							(mid -0.249642 0.249642)
							(end -0.1778 0.2794)
						)
						(arc
							(start 0.1778 0.2794)
							(mid 0.249642 0.249642)
							(end 0.2794 0.1778)
						)
						(arc
							(start 0.2794 -0.1778)
							(mid 0.249642 -0.249642)
							(end 0.1778 -0.2794)
						)
					)
					(width 0)
					(fill yes)
				)
			)
		)
		(pad "2" smd custom
			(at 0 0.4445 270)
			(size 0.1397 0.1397)
			(layers "F.Cu" "F.Mask" "F.Paste")
			(net "I2C_SCC_B_SDA_BUF")
			(options
				(clearance outline)
				(anchor circle)
			)
			(primitives
				(gr_poly
					(pts
						(arc
							(start -0.1778 -0.2794)
							(mid -0.249642 -0.249642)
							(end -0.2794 -0.1778)
						)
						(arc
							(start -0.2794 0.1778)
							(mid -0.249642 0.249642)
							(end -0.1778 0.2794)
						)
						(arc
							(start 0.1778 0.2794)
							(mid 0.249642 0.249642)
							(end 0.2794 0.1778)
						)
						(arc
							(start 0.2794 -0.1778)
							(mid 0.249642 -0.249642)
							(end 0.1778 -0.2794)
						)
					)
					(width 0)
					(fill yes)
				)
			)
		)
	)
	(footprint ""
		(layer "F.Cu")
		(at 40.252396 -360.9594)
		(property "Reference" "C66"
			(at 0 0 0)
			(layer "F.SilkS")
			(hide yes)
			(effects
				(font
					(size 1.27 1.27)
				)
			)
		)
		(property "Value" "SCD1U16V2KX-3GP"
			(at 1.1811 -2.7051 0)
			(unlocked yes)
			(layer "F.Fab")
			(hide yes)
			(effects
				(font
					(size 1.016 1.016)
					(thickness 0.1524)
				)
			)
		)
		(property "Device Type" "C402H22"
			(at 1.1811 -4.2291 0)
			(unlocked yes)
			(layer "F.Fab")
			(hide yes)
			(effects
				(font
					(size 1.016 1.016)
					(thickness 0.1524)
				)
			)
		)
		(duplicate_pad_numbers_are_jumpers no)
		(fp_rect
			(start -0.4318 0.9525)
			(end 0.4318 -0.9525)
			(stroke
				(width 0)
				(type default)
			)
			(fill no)
			(layer "F.CrtYd")
		)
		(fp_rect
			(start -0.4318 0.9525)
			(end 0.4318 -0.9525)
			(stroke
				(width 0)
				(type default)
			)
			(fill no)
			(layer "F.Fab")
		)
		(pad "1" smd custom
			(at 0 -0.4445)
			(size 0.1524 0.1524)
			(layers "F.Cu" "F.Mask" "F.Paste")
			(net "P3V3_IN")
			(options
				(clearance outline)
				(anchor circle)
			)
			(primitives
				(gr_poly
					(pts
						(arc
							(start 0.3048 -0.2032)
							(mid 0.275042 -0.275042)
							(end 0.2032 -0.3048)
						)
						(arc
							(start -0.2032 -0.3048)
							(mid -0.275042 -0.275042)
							(end -0.3048 -0.2032)
						)
						(arc
							(start -0.3048 0.2032)
							(mid -0.275042 0.275042)
							(end -0.2032 0.3048)
						)
						(arc
							(start 0.2032 0.3048)
							(mid 0.275042 0.275042)
							(end 0.3048 0.2032)
						)
					)
					(width 0)
					(fill yes)
				)
			)
		)
		(pad "2" smd custom
			(at 0 0.4445)
			(size 0.1524 0.1524)
			(layers "F.Cu" "F.Mask" "F.Paste")
			(net "GND")
			(options
				(clearance outline)
				(anchor circle)
			)
			(primitives
				(gr_poly
					(pts
						(arc
							(start 0.3048 -0.2032)
							(mid 0.275042 -0.275042)
							(end 0.2032 -0.3048)
						)
						(arc
							(start -0.2032 -0.3048)
							(mid -0.275042 -0.275042)
							(end -0.3048 -0.2032)
						)
						(arc
							(start -0.3048 0.2032)
							(mid -0.275042 0.275042)
							(end -0.2032 0.3048)
						)
						(arc
							(start 0.2032 0.3048)
							(mid 0.275042 0.275042)
							(end 0.3048 0.2032)
						)
					)
					(width 0)
					(fill yes)
				)
			)
		)
	)
	(footprint ""
		(layer "F.Cu")
		(at 221.73946 -163.37026 -90)
		(property "Reference" "R54"
			(at 0 0 270)
			(layer "F.SilkS")
			(hide yes)
			(effects
				(font
					(size 1.27 1.27)
				)
			)
		)
		(property "Value" "4K7R2F-GP"
			(at 0.064008 -3.993896 270)
			(unlocked yes)
			(layer "F.Fab")
			(hide yes)
			(effects
				(font
					(size 1.016 1.016)
					(thickness 0.1524)
				)
			)
		)
		(property "Device Type" "R402H16"
			(at 0.064008 -5.517896 270)
			(unlocked yes)
			(layer "F.Fab")
			(hide yes)
			(effects
				(font
					(size 1.016 1.016)
					(thickness 0.1524)
				)
			)
		)
		(duplicate_pad_numbers_are_jumpers no)
		(fp_line
			(start -0.508 -0.9398)
			(end -0.508 0.9398)
			(stroke
				(width 0.1524)
				(type default)
			)
			(layer "F.SilkS")
		)
		(fp_line
			(start 0.508 -0.9398)
			(end -0.508 -0.9398)
			(stroke
				(width 0.1524)
				(type default)
			)
			(layer "F.SilkS")
		)
		(fp_rect
			(start -0.508 0.9398)
			(end 0.508 -0.9398)
			(stroke
				(width 0)
				(type default)
			)
			(fill no)
			(layer "F.CrtYd")
		)
		(fp_rect
			(start -0.508 0.9398)
			(end 0.508 -0.9398)
			(stroke
				(width 0)
				(type default)
			)
			(fill no)
			(layer "F.Fab")
		)
		(pad "1" smd custom
			(at 0 -0.4445 270)
			(size 0.1397 0.1397)
			(layers "F.Cu" "F.Mask" "F.Paste")
			(net "P3V3_STBY_B")
			(options
				(clearance outline)
				(anchor circle)
			)
			(primitives
				(gr_poly
					(pts
						(arc
							(start -0.1778 -0.2794)
							(mid -0.249642 -0.249642)
							(end -0.2794 -0.1778)
						)
						(arc
							(start -0.2794 0.1778)
							(mid -0.249642 0.249642)
							(end -0.1778 0.2794)
						)
						(arc
							(start 0.1778 0.2794)
							(mid 0.249642 0.249642)
							(end 0.2794 0.1778)
						)
						(arc
							(start 0.2794 -0.1778)
							(mid 0.249642 -0.249642)
							(end 0.1778 -0.2794)
						)
					)
					(width 0)
					(fill yes)
				)
			)
		)
		(pad "2" smd custom
			(at 0 0.4445 270)
			(size 0.1397 0.1397)
			(layers "F.Cu" "F.Mask" "F.Paste")
			(net "IO_EXP6_A1")
			(options
				(clearance outline)
				(anchor circle)
			)
			(primitives
				(gr_poly
					(pts
						(arc
							(start -0.1778 -0.2794)
							(mid -0.249642 -0.249642)
							(end -0.2794 -0.1778)
						)
						(arc
							(start -0.2794 0.1778)
							(mid -0.249642 0.249642)
							(end -0.1778 0.2794)
						)
						(arc
							(start 0.1778 0.2794)
							(mid 0.249642 0.249642)
							(end 0.2794 0.1778)
						)
						(arc
							(start 0.2794 -0.1778)
							(mid 0.249642 -0.249642)
							(end 0.1778 -0.2794)
						)
					)
					(width 0)
					(fill yes)
				)
			)
		)
	)
	(footprint ""
		(layer "F.Cu")
		(at 29.431996 -369.7478 180)
		(property "Reference" "U49"
			(at 0 0 180)
			(layer "F.SilkS")
			(hide yes)
			(effects
				(font
					(size 1.27 1.27)
				)
			)
		)
		(property "Value" "SN74LVC1G08DCKR-GP"
			(at -2.3368 -8.6868 180)
			(unlocked yes)
			(layer "F.Fab")
			(hide yes)
			(effects
				(font
					(size 1.016 1.016)
					(thickness 0.1524)
				)
			)
		)
		(property "Device Type" "SC70-5H44"
			(at -2.3114 -10.414 180)
			(unlocked yes)
			(layer "F.Fab")
			(hide yes)
			(effects
				(font
					(size 1.016 1.016)
					(thickness 0.1524)
				)
			)
		)
		(duplicate_pad_numbers_are_jumpers no)
		(fp_line
			(start 1.3843 -1.8034)
			(end 1.3843 -1.1176)
			(stroke
				(width 0.3302)
				(type default)
			)
			(layer "F.SilkS")
		)
		(fp_line
			(start 1.27 1.7018)
			(end -1.27 1.7018)
			(stroke
				(width 0.1524)
				(type default)
			)
			(layer "F.SilkS")
		)
		(fp_line
			(start 1.27 -1.7018)
			(end 1.27 1.7018)
			(stroke
				(width 0.1524)
				(type default)
			)
			(layer "F.SilkS")
		)
		(fp_line
			(start 0.6604 -1.8034)
			(end 1.3843 -1.8034)
			(stroke
				(width 0.3302)
				(type default)
			)
			(layer "F.SilkS")
		)
		(fp_line
			(start -1.27 1.7018)
			(end -1.27 -1.7018)
			(stroke
				(width 0.1524)
				(type default)
			)
			(layer "F.SilkS")
		)
		(fp_line
			(start -1.27 -1.7018)
			(end 1.27 -1.7018)
			(stroke
				(width 0.1524)
				(type default)
			)
			(layer "F.SilkS")
		)
		(fp_rect
			(start -1.524 1.9558)
			(end 1.524 -1.9558)
			(stroke
				(width 0)
				(type default)
			)
			(fill no)
			(layer "F.CrtYd")
		)
		(fp_poly
			(pts
				(xy -1.524 -1.9558) (xy 1.524 -1.9558) (xy 1.524 1.9558) (xy -1.524 1.9558)
			)
			(stroke
				(width 0)
				(type default)
			)
			(fill no)
			(layer "F.Fab")
		)
		(pad "1" smd rect
			(at 0.65024 -0.8255 180)
			(size 0.4064 1.2192)
			(layers "F.Cu" "F.Mask" "F.Paste")
			(net "RDPB_FAN_LED0")
		)
		(pad "2" smd rect
			(at 0 -0.8255 180)
			(size 0.4064 1.2192)
			(layers "F.Cu" "F.Mask" "F.Paste")
			(net "FDPB_FAN_LED0")
		)
		(pad "3" smd rect
			(at -0.65024 -0.8255 180)
			(size 0.4064 1.2192)
			(layers "F.Cu" "F.Mask" "F.Paste")
			(net "GND")
		)
		(pad "4" smd rect
			(at -0.65024 0.8255 180)
			(size 0.4064 1.2192)
			(layers "F.Cu" "F.Mask" "F.Paste")
			(net "FAN_LED0")
		)
		(pad "5" smd rect
			(at 0.65024 0.8255 180)
			(size 0.4064 1.2192)
			(layers "F.Cu" "F.Mask" "F.Paste")
			(net "P3V3_IN")
		)
	)
	(footprint ""
		(layer "F.Cu")
		(at 209.941668 -356.274624 90)
		(property "Reference" "R1020"
			(at 0 0 90)
			(layer "F.SilkS")
			(hide yes)
			(effects
				(font
					(size 1.27 1.27)
				)
			)
		)
		(property "Value" "10R5F-1-GP"
			(at 0 -8.9535 90)
			(unlocked yes)
			(layer "F.Fab")
			(hide yes)
			(effects
				(font
					(size 1.27 1.016)
					(thickness 0.1524)
				)
			)
		)
		(property "Device Type" "R805H24"
			(at 0 -10.6299 90)
			(unlocked yes)
			(layer "F.Fab")
			(hide yes)
			(effects
				(font
					(size 1.27 1.016)
					(thickness 0.1524)
				)
			)
		)
		(duplicate_pad_numbers_are_jumpers no)
		(fp_line
			(start 0.889 -1.7018)
			(end -0.889 -1.7018)
			(stroke
				(width 0.1524)
				(type default)
			)
			(layer "F.SilkS")
		)
		(fp_line
			(start 0.889 -1.7018)
			(end 0.889 -0.381)
			(stroke
				(width 0.1524)
				(type default)
			)
			(layer "F.SilkS")
		)
		(fp_line
			(start -0.889 -1.7018)
			(end -0.889 0.2794)
			(stroke
				(width 0.1524)
				(type default)
			)
			(layer "F.SilkS")
		)
		(fp_line
			(start -0.889 0.0762)
			(end -0.889 1.7018)
			(stroke
				(width 0.1524)
				(type default)
			)
			(layer "F.SilkS")
		)
		(fp_line
			(start 0.889 1.7018)
			(end 0.889 -0.508)
			(stroke
				(width 0.1524)
				(type default)
			)
			(layer "F.SilkS")
		)
		(fp_line
			(start -0.889 1.7018)
			(end 0.889 1.7018)
			(stroke
				(width 0.1524)
				(type default)
			)
			(layer "F.SilkS")
		)
		(fp_poly
			(pts
				(xy 0.9652 -1.778) (xy 0.9652 1.778) (xy -0.9652 1.778) (xy -0.9652 -1.778)
			)
			(stroke
				(width 0)
				(type default)
			)
			(fill no)
			(layer "F.CrtYd")
		)
		(fp_rect
			(start -0.9652 1.778)
			(end 0.9652 -1.778)
			(stroke
				(width 0)
				(type default)
			)
			(fill no)
			(layer "F.Fab")
		)
		(pad "1" smd rect
			(at 0 -0.9652 90)
			(size 1.397 1.143)
			(layers "F.Cu" "F.Mask" "F.Paste")
			(net "MB0_12V_CTRL_GATE6")
		)
		(pad "2" smd rect
			(at 0 0.9652 90)
			(size 1.397 1.143)
			(layers "F.Cu" "F.Mask" "F.Paste")
			(net "MB0_CM_GATE_R")
		)
	)
	(footprint ""
		(layer "F.Cu")
		(at 44.225718 -112.809274 90)
		(property "Reference" "C639"
			(at 0 0 90)
			(layer "F.SilkS")
			(hide yes)
			(effects
				(font
					(size 1.27 1.27)
				)
			)
		)
		(property "Value" "SC10U16V5KX-7-GP-U"
			(at -0.0762 -6.1214 90)
			(unlocked yes)
			(layer "F.Fab")
			(hide yes)
			(effects
				(font
					(size 1.016 1.016)
					(thickness 0.1524)
				)
			)
		)
		(property "Device Type" "C805H58"
			(at -0.0762 -8.1534 90)
			(unlocked yes)
			(layer "F.Fab")
			(hide yes)
			(effects
				(font
					(size 1.016 1.016)
					(thickness 0.1524)
				)
			)
		)
		(duplicate_pad_numbers_are_jumpers no)
		(fp_line
			(start 0.635 0)
			(end -0.635 0)
			(stroke
				(width 0.508)
				(type default)
			)
			(layer "F.SilkS")
		)
		(fp_rect
			(start -0.9652 1.778)
			(end 0.9652 -1.778)
			(stroke
				(width 0)
				(type default)
			)
			(fill no)
			(layer "F.CrtYd")
		)
		(fp_poly
			(pts
				(xy -0.9652 -1.778) (xy 0.9652 -1.778) (xy 0.9652 1.778) (xy -0.9652 1.778)
			)
			(stroke
				(width 0)
				(type default)
			)
			(fill no)
			(layer "F.Fab")
		)
		(pad "1" smd rect
			(at 0 -0.9652 90)
			(size 1.397 1.143)
			(layers "F.Cu" "F.Mask" "F.Paste")
			(net "P12V_B_2_VIN_U32")
		)
		(pad "2" smd rect
			(at 0 0.9652 90)
			(size 1.397 1.143)
			(layers "F.Cu" "F.Mask" "F.Paste")
			(net "GND")
		)
	)
	(footprint ""
		(layer "F.Cu")
		(at 364.236 -20.574 90)
		(property "Reference" "C441"
			(at 0 0 90)
			(layer "F.SilkS")
			(hide yes)
			(effects
				(font
					(size 1.27 1.27)
				)
			)
		)
		(property "Value" "SCD033U25V2KX-GP"
			(at 1.1811 -2.7051 90)
			(unlocked yes)
			(layer "F.Fab")
			(hide yes)
			(effects
				(font
					(size 1.016 1.016)
					(thickness 0.1524)
				)
			)
		)
		(property "Device Type" "C402H22"
			(at 1.1811 -4.2291 90)
			(unlocked yes)
			(layer "F.Fab")
			(hide yes)
			(effects
				(font
					(size 1.016 1.016)
					(thickness 0.1524)
				)
			)
		)
		(duplicate_pad_numbers_are_jumpers no)
		(fp_rect
			(start -0.4318 0.9525)
			(end 0.4318 -0.9525)
			(stroke
				(width 0)
				(type default)
			)
			(fill no)
			(layer "F.CrtYd")
		)
		(fp_rect
			(start -0.4318 0.9525)
			(end 0.4318 -0.9525)
			(stroke
				(width 0)
				(type default)
			)
			(fill no)
			(layer "F.Fab")
		)
		(pad "1" smd custom
			(at 0 -0.4445 90)
			(size 0.1524 0.1524)
			(layers "F.Cu" "F.Mask" "F.Paste")
			(net "SW_HDD_P31")
			(options
				(clearance outline)
				(anchor circle)
			)
			(primitives
				(gr_poly
					(pts
						(arc
							(start 0.3048 -0.2032)
							(mid 0.275042 -0.275042)
							(end 0.2032 -0.3048)
						)
						(arc
							(start -0.2032 -0.3048)
							(mid -0.275042 -0.275042)
							(end -0.3048 -0.2032)
						)
						(arc
							(start -0.3048 0.2032)
							(mid -0.275042 0.275042)
							(end -0.2032 0.3048)
						)
						(arc
							(start 0.2032 0.3048)
							(mid 0.275042 0.275042)
							(end 0.3048 0.2032)
						)
					)
					(width 0)
					(fill yes)
				)
			)
		)
		(pad "2" smd custom
			(at 0 0.4445 90)
			(size 0.1524 0.1524)
			(layers "F.Cu" "F.Mask" "F.Paste")
			(net "GND")
			(options
				(clearance outline)
				(anchor circle)
			)
			(primitives
				(gr_poly
					(pts
						(arc
							(start 0.3048 -0.2032)
							(mid 0.275042 -0.275042)
							(end 0.2032 -0.3048)
						)
						(arc
							(start -0.2032 -0.3048)
							(mid -0.275042 -0.275042)
							(end -0.3048 -0.2032)
						)
						(arc
							(start -0.3048 0.2032)
							(mid -0.275042 0.275042)
							(end -0.2032 0.3048)
						)
						(arc
							(start 0.2032 0.3048)
							(mid 0.275042 0.275042)
							(end 0.3048 0.2032)
						)
					)
					(width 0)
					(fill yes)
				)
			)
		)
	)
	(footprint ""
		(layer "F.Cu")
		(at 334.7466 -16.3576 180)
		(property "Reference" "D30"
			(at 0 0 180)
			(layer "F.SilkS")
			(hide yes)
			(effects
				(font
					(size 1.27 1.27)
				)
			)
		)
		(property "Value" "RB551V30-GP"
			(at 0 -6.7818 180)
			(unlocked yes)
			(layer "F.Fab")
			(hide yes)
			(effects
				(font
					(size 1.016 1.016)
					(thickness 0.1524)
				)
			)
		)
		(property "Device Type" "SOD323AKH38"
			(at 0 -8.6868 180)
			(unlocked yes)
			(layer "F.Fab")
			(hide yes)
			(effects
				(font
					(size 1.016 1.016)
					(thickness 0.1524)
				)
			)
		)
		(duplicate_pad_numbers_are_jumpers no)
		(fp_line
			(start 0.889 2.159)
			(end -0.889 2.159)
			(stroke
				(width 0.1524)
				(type default)
			)
			(layer "F.SilkS")
		)
		(fp_line
			(start 0.889 -1.9304)
			(end 0.889 2.159)
			(stroke
				(width 0.1524)
				(type default)
			)
			(layer "F.SilkS")
		)
		(fp_line
			(start 0.762 2.0574)
			(end -0.762 2.0574)
			(stroke
				(width 0.508)
				(type default)
			)
			(layer "F.SilkS")
		)
		(fp_line
			(start -0.889 2.159)
			(end -0.889 -1.9304)
			(stroke
				(width 0.1524)
				(type default)
			)
			(layer "F.SilkS")
		)
		(fp_line
			(start -0.889 -1.9304)
			(end 0.889 -1.9304)
			(stroke
				(width 0.1524)
				(type default)
			)
			(layer "F.SilkS")
		)
		(fp_rect
			(start -1.016 2.3114)
			(end 1.016 -2.0066)
			(stroke
				(width 0)
				(type default)
			)
			(fill no)
			(layer "F.CrtYd")
		)
		(fp_poly
			(pts
				(xy -1.016 -2.0066) (xy 1.016 -2.0066) (xy 1.016 2.3114) (xy -1.016 2.3114)
			)
			(stroke
				(width 0)
				(type default)
			)
			(fill no)
			(layer "F.Fab")
		)
		(pad "A" smd rect
			(at 0 -1.143 180)
			(size 0.5588 1.016)
			(layers "F.Cu" "F.Mask" "F.Paste")
			(net "SW_HDD_R30")
		)
		(pad "K" smd rect
			(at 0 1.143 180)
			(size 0.5588 1.016)
			(layers "F.Cu" "F.Mask" "F.Paste")
			(net "SW_HDD_N30")
		)
	)
)
